# SCM (Grand Teton) — schematic netlist excerpt (pin names and nets, part order shuffled) for the footprints in the layout excerpt that follows; sources: Cadence DE-HDL packaged netlist, KiCad conversion of 12092022_DA0F0TMDCD0_F0T_Management_Board_D_brd_V3_OCP.brd

R619  Q_RES  8.2K 5% EMPTY  pkg 0402LF  page 49 : A = HDD_LED_N ; B = GND
R185  Q_RES  33.2 1% CHIP  pkg 0402LF  page 14 : A = I3C1_SPD_SDA ; B = I3C1_SDA_R

(kicad_pcb
	(version 20260206)
	(generator "pcbnew")
	(generator_version "10.0")
	(general
		(thickness 1.6)
		(legacy_teardrops no)
	)
	(paper "A4")
	(title_block
		(title "12092022_DA0F0TMDCD0_F0T_Management_Board_D_brd_V3_OCP.brd")
		(comment 1 "Grand Teton / footprints 673-674 of 1440")
	)
	(layers
		(0 "F.Cu" signal "TOP")
		(4 "In1.Cu" signal "GND")
		(6 "In2.Cu" signal "IN1")
		(8 "In3.Cu" signal "GND1")
		(10 "In4.Cu" signal "IN2")
		(12 "In5.Cu" signal "VCC")
		(14 "In6.Cu" signal "VCC1")
		(16 "In7.Cu" signal "IN3")
		(18 "In8.Cu" signal "GND2")
		(20 "In9.Cu" signal "IN4")
		(22 "In10.Cu" signal "GND3")
		(2 "B.Cu" signal "BOTTOM")
		(9 "F.Adhes" user "F.Adhesive")
		(11 "B.Adhes" user "B.Adhesive")
		(13 "F.Paste" user "Package Geometry/Pastemask Top")
		(15 "B.Paste" user "Package Geometry/Pastemask Bottom")
		(5 "F.SilkS" user "Ref Des/Silkscreen Top")
		(7 "B.SilkS" user "Ref Des/Silkscreen Bottom")
		(1 "F.Mask" user "Board Geometry/Soldermask Top")
		(3 "B.Mask" user "Board Geometry/Soldermask Bottom")
		(17 "Dwgs.User" user "User.Drawings")
		(19 "Cmts.User" user "User.Comments")
		(21 "Eco1.User" user "User.Eco1")
		(23 "Eco2.User" user "User.Eco2")
		(25 "Edge.Cuts" user "Board Geometry/Outline")
		(27 "Margin" user)
		(31 "F.CrtYd" user "Package Geometry/Place Bound Top")
		(29 "B.CrtYd" user "Package Geometry/Place Bound Bottom")
		(35 "F.Fab" user "Ref Des/Assembly Top")
		(33 "B.Fab" user "Ref Des/Assembly Bottom")
	)
	(footprint ""
		(layer "F.Cu")
		(at 40.887142 -63.756794 -90)
		(property "Reference" "R185"
			(at 0 0 270)
			(layer "F.SilkS")
			(hide yes)
			(effects
				(font
					(size 1.27 1.27)
				)
			)
		)
		(property "Value" ""
			(at 0 0 270)
			(layer "F.Fab")
			(effects
				(font
					(size 1.27 1.27)
				)
			)
		)
		(duplicate_pad_numbers_are_jumpers no)
		(fp_line
			(start -0.7874 0.4064)
			(end -0.7874 -0.4064)
			(stroke
				(width 0.1524)
				(type default)
			)
			(layer "F.SilkS")
		)
		(fp_line
			(start 0.7874 0.4064)
			(end -0.7874 0.4064)
			(stroke
				(width 0.1524)
				(type default)
			)
			(layer "F.SilkS")
		)
		(fp_line
			(start -0.7874 -0.4064)
			(end 0.7874 -0.4064)
			(stroke
				(width 0.1524)
				(type default)
			)
			(layer "F.SilkS")
		)
		(fp_line
			(start 0.7874 -0.4064)
			(end 0.7874 0.4064)
			(stroke
				(width 0.1524)
				(type default)
			)
			(layer "F.SilkS")
		)
		(fp_line
			(start -0.67945 0.3048)
			(end -0.67945 -0.305054)
			(stroke
				(width 0.1)
				(type default)
			)
			(layer "F.Fab")
		)
		(fp_line
			(start -0.12065 0.3048)
			(end -0.67945 0.3048)
			(stroke
				(width 0.1)
				(type default)
			)
			(layer "F.Fab")
		)
		(fp_line
			(start 0.120396 0.3048)
			(end 0.120396 0.2794)
			(stroke
				(width 0.1)
				(type default)
			)
			(layer "F.Fab")
		)
		(fp_line
			(start 0.67945 0.3048)
			(end 0.120396 0.3048)
			(stroke
				(width 0.1)
				(type default)
			)
			(layer "F.Fab")
		)
		(fp_line
			(start -0.12065 0.2794)
			(end -0.12065 0.3048)
			(stroke
				(width 0.1)
				(type default)
			)
			(layer "F.Fab")
		)
		(fp_line
			(start 0.120396 0.2794)
			(end -0.12065 0.2794)
			(stroke
				(width 0.1)
				(type default)
			)
			(layer "F.Fab")
		)
		(fp_line
			(start -0.12065 -0.2794)
			(end 0.12065 -0.2794)
			(stroke
				(width 0.1)
				(type default)
			)
			(layer "F.Fab")
		)
		(fp_line
			(start 0.12065 -0.2794)
			(end 0.12065 -0.3048)
			(stroke
				(width 0.1)
				(type default)
			)
			(layer "F.Fab")
		)
		(fp_line
			(start 0.12065 -0.3048)
			(end 0.67945 -0.3048)
			(stroke
				(width 0.1)
				(type default)
			)
			(layer "F.Fab")
		)
		(fp_line
			(start 0.67945 -0.3048)
			(end 0.67945 0.3048)
			(stroke
				(width 0.1)
				(type default)
			)
			(layer "F.Fab")
		)
		(fp_line
			(start -0.67945 -0.305054)
			(end -0.12065 -0.305054)
			(stroke
				(width 0.1)
				(type default)
			)
			(layer "F.Fab")
		)
		(fp_line
			(start -0.12065 -0.305054)
			(end -0.12065 -0.2794)
			(stroke
				(width 0.1)
				(type default)
			)
			(layer "F.Fab")
		)
		(pad "1" smd circle
			(at -0.40005 0 270)
			(size 0 0)
			(layers "F.Cu" "F.Mask" "F.Paste")
			(net "I3C1_SPD_SDA")
		)
		(pad "2" smd circle
			(at 0.40005 0 270)
			(size 0 0)
			(layers "F.Cu" "F.Mask" "F.Paste")
			(net "I3C1_SDA_R")
		)
	)
	(footprint ""
		(layer "F.Cu")
		(at 13.335 -16.383 90)
		(property "Reference" "R619"
			(at 0 0 90)
			(layer "F.SilkS")
			(hide yes)
			(effects
				(font
					(size 1.27 1.27)
				)
			)
		)
		(property "Value" ""
			(at 0 0 90)
			(layer "F.Fab")
			(effects
				(font
					(size 1.27 1.27)
				)
			)
		)
		(duplicate_pad_numbers_are_jumpers no)
		(fp_line
			(start 0.7874 -0.4064)
			(end 0.7874 0.4064)
			(stroke
				(width 0.1524)
				(type default)
			)
			(layer "F.SilkS")
		)
		(fp_line
			(start -0.7874 -0.4064)
			(end 0.7874 -0.4064)
			(stroke
				(width 0.1524)
				(type default)
			)
			(layer "F.SilkS")
		)
		(fp_line
			(start 0.7874 0.4064)
			(end -0.7874 0.4064)
			(stroke
				(width 0.1524)
				(type default)
			)
			(layer "F.SilkS")
		)
		(fp_line
			(start -0.7874 0.4064)
			(end -0.7874 -0.4064)
			(stroke
				(width 0.1524)
				(type default)
			)
			(layer "F.SilkS")
		)
		(fp_line
			(start -0.12065 -0.305054)
			(end -0.12065 -0.2794)
			(stroke
				(width 0.1)
				(type default)
			)
			(layer "F.Fab")
		)
		(fp_line
			(start -0.67945 -0.305054)
			(end -0.12065 -0.305054)
			(stroke
				(width 0.1)
				(type default)
			)
			(layer "F.Fab")
		)
		(fp_line
			(start 0.67945 -0.3048)
			(end 0.67945 0.3048)
			(stroke
				(width 0.1)
				(type default)
			)
			(layer "F.Fab")
		)
		(fp_line
			(start 0.12065 -0.3048)
			(end 0.67945 -0.3048)
			(stroke
				(width 0.1)
				(type default)
			)
			(layer "F.Fab")
		)
		(fp_line
			(start 0.12065 -0.2794)
			(end 0.12065 -0.3048)
			(stroke
				(width 0.1)
				(type default)
			)
			(layer "F.Fab")
		)
		(fp_line
			(start -0.12065 -0.2794)
			(end 0.12065 -0.2794)
			(stroke
				(width 0.1)
				(type default)
			)
			(layer "F.Fab")
		)
		(fp_line
			(start 0.120396 0.2794)
			(end -0.12065 0.2794)
			(stroke
				(width 0.1)
				(type default)
			)
			(layer "F.Fab")
		)
		(fp_line
			(start -0.12065 0.2794)
			(end -0.12065 0.3048)
			(stroke
				(width 0.1)
				(type default)
			)
			(layer "F.Fab")
		)
		(fp_line
			(start 0.67945 0.3048)
			(end 0.120396 0.3048)
			(stroke
				(width 0.1)
				(type default)
			)
			(layer "F.Fab")
		)
		(fp_line
			(start 0.120396 0.3048)
			(end 0.120396 0.2794)
			(stroke
				(width 0.1)
				(type default)
			)
			(layer "F.Fab")
		)
		(fp_line
			(start -0.12065 0.3048)
			(end -0.67945 0.3048)
			(stroke
				(width 0.1)
				(type default)
			)
			(layer "F.Fab")
		)
		(fp_line
			(start -0.67945 0.3048)
			(end -0.67945 -0.305054)
			(stroke
				(width 0.1)
				(type default)
			)
			(layer "F.Fab")
		)
		(pad "1" smd circle
			(at -0.40005 0 90)
			(size 0 0)
			(layers "F.Cu" "F.Mask" "F.Paste")
			(net "HDD_LED_N")
		)
		(pad "2" smd circle
			(at 0.40005 0 90)
			(size 0 0)
			(layers "F.Cu" "F.Mask" "F.Paste")
			(net "GND")
		)
	)
)
